(kicad_pcb
	(version 20260206)
	(generator "pcbnew")
	(generator_version "10.0")
	(general
		(thickness 1.6)
		(legacy_teardrops no)
	)
	(paper "A4")
	(title_block
		(title "03242023_DA0F0TMBIJ0_F0T_Motherboard_J_brd_V01_OCP.brd")
		(comment 1 "Grand Teton / footprints 5672-5678 of 6105")
	)
	(layers
		(0 "F.Cu" signal "TOP")
		(4 "In1.Cu" signal "GND")
		(6 "In2.Cu" signal "IN1")
		(8 "In3.Cu" signal "GND1")
		(10 "In4.Cu" signal "IN2")
		(12 "In5.Cu" signal "GND2")
		(14 "In6.Cu" signal "IN3")
		(16 "In7.Cu" signal "GND3")
		(18 "In8.Cu" signal "VCC")
		(20 "In9.Cu" signal "VCC1")
		(22 "In10.Cu" signal "GND4")
		(24 "In11.Cu" signal "IN4")
		(26 "In12.Cu" signal "GND5")
		(28 "In13.Cu" signal "IN5")
		(30 "In14.Cu" signal "GND6")
		(32 "In15.Cu" signal "IN6")
		(34 "In16.Cu" signal "GND7")
		(2 "B.Cu" signal "BOTTOM")
		(9 "F.Adhes" user "F.Adhesive")
		(11 "B.Adhes" user "B.Adhesive")
		(13 "F.Paste" user "Package Geometry/Pastemask Top")
		(15 "B.Paste" user "Package Geometry/Pastemask Bottom")
		(5 "F.SilkS" user "Ref Des/Silkscreen Top")
		(7 "B.SilkS" user "Ref Des/Silkscreen Bottom")
		(1 "F.Mask" user "Board Geometry/Soldermask Top")
		(3 "B.Mask" user "Board Geometry/Soldermask Bottom")
		(17 "Dwgs.User" user "User.Drawings")
		(19 "Cmts.User" user "User.Comments")
		(21 "Eco1.User" user "User.Eco1")
		(23 "Eco2.User" user "User.Eco2")
		(25 "Edge.Cuts" user "Board Geometry/Outline")
		(27 "Margin" user)
		(31 "F.CrtYd" user "Package Geometry/Place Bound Top")
		(29 "B.CrtYd" user "Package Geometry/Place Bound Bottom")
		(35 "F.Fab" user "Ref Des/Assembly Top")
		(33 "B.Fab" user "Ref Des/Assembly Bottom")
	)
	(footprint ""
		(layer "B.Cu")
		(at 67.320922 -183.303926 -90)
		(property "Reference" "R155"
			(at 0 0 90)
			(layer "B.SilkS")
			(hide yes)
			(effects
				(font
					(size 1.27 1.27)
				)
				(justify mirror)
			)
		)
		(property "Value" ""
			(at 0 0 90)
			(layer "B.Fab")
			(effects
				(font
					(size 1.27 1.27)
				)
				(justify mirror)
			)
		)
		(duplicate_pad_numbers_are_jumpers no)
		(fp_line
			(start -0.7874 0.4064)
			(end 0.7874 0.4064)
			(stroke
				(width 0.1524)
				(type default)
			)
			(layer "B.SilkS")
		)
		(fp_line
			(start 0.7874 0.4064)
			(end 0.7874 -0.4064)
			(stroke
				(width 0.1524)
				(type default)
			)
			(layer "B.SilkS")
		)
		(fp_line
			(start -0.7874 -0.4064)
			(end -0.7874 0.4064)
			(stroke
				(width 0.1524)
				(type default)
			)
			(layer "B.SilkS")
		)
		(fp_line
			(start 0.7874 -0.4064)
			(end -0.7874 -0.4064)
			(stroke
				(width 0.1524)
				(type default)
			)
			(layer "B.SilkS")
		)
		(fp_line
			(start -0.67945 0.3048)
			(end -0.120396 0.3048)
			(stroke
				(width 0.1)
				(type default)
			)
			(layer "B.Fab")
		)
		(fp_line
			(start -0.120396 0.3048)
			(end -0.120396 0.2794)
			(stroke
				(width 0.1)
				(type default)
			)
			(layer "B.Fab")
		)
		(fp_line
			(start 0.12065 0.3048)
			(end 0.67945 0.3048)
			(stroke
				(width 0.1)
				(type default)
			)
			(layer "B.Fab")
		)
		(fp_line
			(start 0.67945 0.3048)
			(end 0.67945 -0.305054)
			(stroke
				(width 0.1)
				(type default)
			)
			(layer "B.Fab")
		)
		(fp_line
			(start -0.120396 0.2794)
			(end 0.12065 0.2794)
			(stroke
				(width 0.1)
				(type default)
			)
			(layer "B.Fab")
		)
		(fp_line
			(start 0.12065 0.2794)
			(end 0.12065 0.3048)
			(stroke
				(width 0.1)
				(type default)
			)
			(layer "B.Fab")
		)
		(fp_line
			(start -0.12065 -0.2794)
			(end -0.12065 -0.3048)
			(stroke
				(width 0.1)
				(type default)
			)
			(layer "B.Fab")
		)
		(fp_line
			(start 0.12065 -0.2794)
			(end -0.12065 -0.2794)
			(stroke
				(width 0.1)
				(type default)
			)
			(layer "B.Fab")
		)
		(fp_line
			(start -0.67945 -0.3048)
			(end -0.67945 0.3048)
			(stroke
				(width 0.1)
				(type default)
			)
			(layer "B.Fab")
		)
		(fp_line
			(start -0.12065 -0.3048)
			(end -0.67945 -0.3048)
			(stroke
				(width 0.1)
				(type default)
			)
			(layer "B.Fab")
		)
		(fp_line
			(start 0.12065 -0.305054)
			(end 0.12065 -0.2794)
			(stroke
				(width 0.1)
				(type default)
			)
			(layer "B.Fab")
		)
		(fp_line
			(start 0.67945 -0.305054)
			(end 0.12065 -0.305054)
			(stroke
				(width 0.1)
				(type default)
			)
			(layer "B.Fab")
		)
		(pad "1" smd circle
			(at 0.40005 0 90)
			(size 0 0)
			(layers "B.Cu" "B.Mask" "B.Paste")
			(net "PWRGD_CPU1_BUF_R")
		)
		(pad "2" smd circle
			(at -0.40005 0 90)
			(size 0 0)
			(layers "B.Cu" "B.Mask" "B.Paste")
			(net "PVNN_TERM_CPU1")
		)
	)
	(footprint ""
		(layer "B.Cu")
		(at 45.872146 -321.554856 -90)
		(property "Reference" "C61"
			(at 0 0 90)
			(layer "B.SilkS")
			(hide yes)
			(effects
				(font
					(size 1.27 1.27)
				)
				(justify mirror)
			)
		)
		(property "Value" ""
			(at 0 0 90)
			(layer "B.Fab")
			(effects
				(font
					(size 1.27 1.27)
				)
				(justify mirror)
			)
		)
		(duplicate_pad_numbers_are_jumpers no)
		(fp_line
			(start -1.524 0.762)
			(end 1.524 0.762)
			(stroke
				(width 0.1524)
				(type default)
			)
			(layer "B.SilkS")
		)
		(fp_line
			(start 1.524 0.762)
			(end 1.524 -0.762)
			(stroke
				(width 0.1524)
				(type default)
			)
			(layer "B.SilkS")
		)
		(fp_line
			(start -1.524 -0.762)
			(end -1.524 0.762)
			(stroke
				(width 0.1524)
				(type default)
			)
			(layer "B.SilkS")
		)
		(fp_line
			(start 1.524 -0.762)
			(end -1.524 -0.762)
			(stroke
				(width 0.1524)
				(type default)
			)
			(layer "B.SilkS")
		)
		(fp_line
			(start -1.1049 0.724916)
			(end -1.1049 -0.724916)
			(stroke
				(width 0.1)
				(type default)
			)
			(layer "B.Fab")
		)
		(fp_line
			(start 1.1049 0.724916)
			(end -1.1049 0.724916)
			(stroke
				(width 0.1)
				(type default)
			)
			(layer "B.Fab")
		)
		(fp_line
			(start -1.1049 -0.724916)
			(end 1.1049 -0.724916)
			(stroke
				(width 0.1)
				(type default)
			)
			(layer "B.Fab")
		)
		(fp_line
			(start 1.1049 -0.724916)
			(end 1.1049 0.724916)
			(stroke
				(width 0.1)
				(type default)
			)
			(layer "B.Fab")
		)
		(pad "1" smd rect
			(at 0.889 0 270)
			(size 1.016 1.27)
			(layers "B.Cu" "B.Mask" "B.Paste")
			(net "P12V_S3_AUX_CPU1_NVDIMM")
		)
		(pad "2" smd rect
			(at -0.889 0 270)
			(size 1.016 1.27)
			(layers "B.Cu" "B.Mask" "B.Paste")
			(net "GND")
		)
	)
	(footprint ""
		(layer "B.Cu")
		(at 233.5022 -251.879608 -90)
		(property "Reference" "C1884"
			(at 0 0 90)
			(layer "B.SilkS")
			(hide yes)
			(effects
				(font
					(size 1.27 1.27)
				)
				(justify mirror)
			)
		)
		(property "Value" ""
			(at 0 0 90)
			(layer "B.Fab")
			(effects
				(font
					(size 1.27 1.27)
				)
				(justify mirror)
			)
		)
		(duplicate_pad_numbers_are_jumpers no)
		(fp_line
			(start -0.7874 0.4064)
			(end 0.7874 0.4064)
			(stroke
				(width 0.1524)
				(type default)
			)
			(layer "B.SilkS")
		)
		(fp_line
			(start 0.7874 0.4064)
			(end 0.7874 -0.4064)
			(stroke
				(width 0.1524)
				(type default)
			)
			(layer "B.SilkS")
		)
		(fp_line
			(start -0.7874 -0.4064)
			(end -0.7874 0.4064)
			(stroke
				(width 0.1524)
				(type default)
			)
			(layer "B.SilkS")
		)
		(fp_line
			(start 0.7874 -0.4064)
			(end -0.7874 -0.4064)
			(stroke
				(width 0.1524)
				(type default)
			)
			(layer "B.SilkS")
		)
		(fp_line
			(start -0.67945 0.3048)
			(end -0.120396 0.3048)
			(stroke
				(width 0.1)
				(type default)
			)
			(layer "B.Fab")
		)
		(fp_line
			(start -0.120396 0.3048)
			(end -0.120396 0.2794)
			(stroke
				(width 0.1)
				(type default)
			)
			(layer "B.Fab")
		)
		(fp_line
			(start 0.12065 0.3048)
			(end 0.67945 0.3048)
			(stroke
				(width 0.1)
				(type default)
			)
			(layer "B.Fab")
		)
		(fp_line
			(start 0.67945 0.3048)
			(end 0.67945 -0.305054)
			(stroke
				(width 0.1)
				(type default)
			)
			(layer "B.Fab")
		)
		(fp_line
			(start -0.120396 0.2794)
			(end 0.12065 0.2794)
			(stroke
				(width 0.1)
				(type default)
			)
			(layer "B.Fab")
		)
		(fp_line
			(start 0.12065 0.2794)
			(end 0.12065 0.3048)
			(stroke
				(width 0.1)
				(type default)
			)
			(layer "B.Fab")
		)
		(fp_line
			(start -0.12065 -0.2794)
			(end -0.12065 -0.3048)
			(stroke
				(width 0.1)
				(type default)
			)
			(layer "B.Fab")
		)
		(fp_line
			(start 0.12065 -0.2794)
			(end -0.12065 -0.2794)
			(stroke
				(width 0.1)
				(type default)
			)
			(layer "B.Fab")
		)
		(fp_line
			(start -0.67945 -0.3048)
			(end -0.67945 0.3048)
			(stroke
				(width 0.1)
				(type default)
			)
			(layer "B.Fab")
		)
		(fp_line
			(start -0.12065 -0.3048)
			(end -0.67945 -0.3048)
			(stroke
				(width 0.1)
				(type default)
			)
			(layer "B.Fab")
		)
		(fp_line
			(start 0.12065 -0.305054)
			(end 0.12065 -0.2794)
			(stroke
				(width 0.1)
				(type default)
			)
			(layer "B.Fab")
		)
		(fp_line
			(start 0.67945 -0.305054)
			(end 0.12065 -0.305054)
			(stroke
				(width 0.1)
				(type default)
			)
			(layer "B.Fab")
		)
		(pad "1" smd circle
			(at 0.40005 0 90)
			(size 0 0)
			(layers "B.Cu" "B.Mask" "B.Paste")
			(net "VFG_3P3A_CLK_GEN")
		)
		(pad "2" smd circle
			(at -0.40005 0 90)
			(size 0 0)
			(layers "B.Cu" "B.Mask" "B.Paste")
			(net "GND")
		)
	)
	(footprint ""
		(layer "B.Cu")
		(at 329.738228 -342.936576 90)
		(property "Reference" "PC241_P0_7"
			(at 0 0 90)
			(layer "B.SilkS")
			(hide yes)
			(effects
				(font
					(size 1.27 1.27)
				)
				(justify mirror)
			)
		)
		(property "Value" ""
			(at 0 0 90)
			(layer "B.Fab")
			(effects
				(font
					(size 1.27 1.27)
				)
				(justify mirror)
			)
		)
		(duplicate_pad_numbers_are_jumpers no)
		(fp_line
			(start 1.524 -0.762)
			(end -1.524 -0.762)
			(stroke
				(width 0.1524)
				(type default)
			)
			(layer "B.SilkS")
		)
		(fp_line
			(start -1.524 -0.762)
			(end -1.524 0.762)
			(stroke
				(width 0.1524)
				(type default)
			)
			(layer "B.SilkS")
		)
		(fp_line
			(start 1.524 0.762)
			(end 1.524 -0.762)
			(stroke
				(width 0.1524)
				(type default)
			)
			(layer "B.SilkS")
		)
		(fp_line
			(start -1.524 0.762)
			(end 1.524 0.762)
			(stroke
				(width 0.1524)
				(type default)
			)
			(layer "B.SilkS")
		)
		(fp_line
			(start 1.1049 -0.724916)
			(end 1.1049 0.724916)
			(stroke
				(width 0.1)
				(type default)
			)
			(layer "B.Fab")
		)
		(fp_line
			(start -1.1049 -0.724916)
			(end 1.1049 -0.724916)
			(stroke
				(width 0.1)
				(type default)
			)
			(layer "B.Fab")
		)
		(fp_line
			(start 1.1049 0.724916)
			(end -1.1049 0.724916)
			(stroke
				(width 0.1)
				(type default)
			)
			(layer "B.Fab")
		)
		(fp_line
			(start -1.1049 0.724916)
			(end -1.1049 -0.724916)
			(stroke
				(width 0.1)
				(type default)
			)
			(layer "B.Fab")
		)
		(pad "1" smd rect
			(at 0.889 0 90)
			(size 1.016 1.27)
			(layers "B.Cu" "B.Mask" "B.Paste")
			(net "SW_P12V_PVCCIN_CPU0_FLT")
		)
		(pad "2" smd rect
			(at -0.889 0 90)
			(size 1.016 1.27)
			(layers "B.Cu" "B.Mask" "B.Paste")
			(net "GND")
		)
	)
	(footprint ""
		(layer "B.Cu")
		(at 430.82718 -50.37582 180)
		(property "Reference" "R4678"
			(at 0 0 0)
			(layer "B.SilkS")
			(hide yes)
			(effects
				(font
					(size 1.27 1.27)
				)
				(justify mirror)
			)
		)
		(property "Value" ""
			(at 0 0 0)
			(layer "B.Fab")
			(effects
				(font
					(size 1.27 1.27)
				)
				(justify mirror)
			)
		)
		(duplicate_pad_numbers_are_jumpers no)
		(fp_line
			(start 0.7874 0.4064)
			(end 0.7874 -0.4064)
			(stroke
				(width 0.1524)
				(type default)
			)
			(layer "B.SilkS")
		)
		(fp_line
			(start 0.7874 -0.4064)
			(end -0.7874 -0.4064)
			(stroke
				(width 0.1524)
				(type default)
			)
			(layer "B.SilkS")
		)
		(fp_line
			(start -0.7874 0.4064)
			(end 0.7874 0.4064)
			(stroke
				(width 0.1524)
				(type default)
			)
			(layer "B.SilkS")
		)
		(fp_line
			(start -0.7874 -0.4064)
			(end -0.7874 0.4064)
			(stroke
				(width 0.1524)
				(type default)
			)
			(layer "B.SilkS")
		)
		(fp_line
			(start 0.67945 0.3048)
			(end 0.67945 -0.305054)
			(stroke
				(width 0.1)
				(type default)
			)
			(layer "B.Fab")
		)
		(fp_line
			(start 0.67945 -0.305054)
			(end 0.12065 -0.305054)
			(stroke
				(width 0.1)
				(type default)
			)
			(layer "B.Fab")
		)
		(fp_line
			(start 0.12065 0.3048)
			(end 0.67945 0.3048)
			(stroke
				(width 0.1)
				(type default)
			)
			(layer "B.Fab")
		)
		(fp_line
			(start 0.12065 0.2794)
			(end 0.12065 0.3048)
			(stroke
				(width 0.1)
				(type default)
			)
			(layer "B.Fab")
		)
		(fp_line
			(start 0.12065 -0.2794)
			(end -0.12065 -0.2794)
			(stroke
				(width 0.1)
				(type default)
			)
			(layer "B.Fab")
		)
		(fp_line
			(start 0.12065 -0.305054)
			(end 0.12065 -0.2794)
			(stroke
				(width 0.1)
				(type default)
			)
			(layer "B.Fab")
		)
		(fp_line
			(start -0.120396 0.3048)
			(end -0.120396 0.2794)
			(stroke
				(width 0.1)
				(type default)
			)
			(layer "B.Fab")
		)
		(fp_line
			(start -0.120396 0.2794)
			(end 0.12065 0.2794)
			(stroke
				(width 0.1)
				(type default)
			)
			(layer "B.Fab")
		)
		(fp_line
			(start -0.12065 -0.2794)
			(end -0.12065 -0.3048)
			(stroke
				(width 0.1)
				(type default)
			)
			(layer "B.Fab")
		)
		(fp_line
			(start -0.12065 -0.3048)
			(end -0.67945 -0.3048)
			(stroke
				(width 0.1)
				(type default)
			)
			(layer "B.Fab")
		)
		(fp_line
			(start -0.67945 0.3048)
			(end -0.120396 0.3048)
			(stroke
				(width 0.1)
				(type default)
			)
			(layer "B.Fab")
		)
		(fp_line
			(start -0.67945 -0.3048)
			(end -0.67945 0.3048)
			(stroke
				(width 0.1)
				(type default)
			)
			(layer "B.Fab")
		)
		(pad "1" smd circle
			(at 0.40005 0)
			(size 0 0)
			(layers "B.Cu" "B.Mask" "B.Paste")
			(net "PWRGD_P5V_ISO_R")
		)
		(pad "2" smd circle
			(at -0.40005 0)
			(size 0 0)
			(layers "B.Cu" "B.Mask" "B.Paste")
			(net "PWRGD_P5V_ISO")
		)
	)
	(footprint ""
		(layer "B.Cu")
		(at 72.655684 -183.303926 -90)
		(property "Reference" "R50"
			(at 0 0 90)
			(layer "B.SilkS")
			(hide yes)
			(effects
				(font
					(size 1.27 1.27)
				)
				(justify mirror)
			)
		)
		(property "Value" ""
			(at 0 0 90)
			(layer "B.Fab")
			(effects
				(font
					(size 1.27 1.27)
				)
				(justify mirror)
			)
		)
		(duplicate_pad_numbers_are_jumpers no)
		(fp_line
			(start -0.7874 0.4064)
			(end 0.7874 0.4064)
			(stroke
				(width 0.1524)
				(type default)
			)
			(layer "B.SilkS")
		)
		(fp_line
			(start 0.7874 0.4064)
			(end 0.7874 -0.4064)
			(stroke
				(width 0.1524)
				(type default)
			)
			(layer "B.SilkS")
		)
		(fp_line
			(start -0.7874 -0.4064)
			(end -0.7874 0.4064)
			(stroke
				(width 0.1524)
				(type default)
			)
			(layer "B.SilkS")
		)
		(fp_line
			(start 0.7874 -0.4064)
			(end -0.7874 -0.4064)
			(stroke
				(width 0.1524)
				(type default)
			)
			(layer "B.SilkS")
		)
		(fp_line
			(start -0.67945 0.3048)
			(end -0.120396 0.3048)
			(stroke
				(width 0.1)
				(type default)
			)
			(layer "B.Fab")
		)
		(fp_line
			(start -0.120396 0.3048)
			(end -0.120396 0.2794)
			(stroke
				(width 0.1)
				(type default)
			)
			(layer "B.Fab")
		)
		(fp_line
			(start 0.12065 0.3048)
			(end 0.67945 0.3048)
			(stroke
				(width 0.1)
				(type default)
			)
			(layer "B.Fab")
		)
		(fp_line
			(start 0.67945 0.3048)
			(end 0.67945 -0.305054)
			(stroke
				(width 0.1)
				(type default)
			)
			(layer "B.Fab")
		)
		(fp_line
			(start -0.120396 0.2794)
			(end 0.12065 0.2794)
			(stroke
				(width 0.1)
				(type default)
			)
			(layer "B.Fab")
		)
		(fp_line
			(start 0.12065 0.2794)
			(end 0.12065 0.3048)
			(stroke
				(width 0.1)
				(type default)
			)
			(layer "B.Fab")
		)
		(fp_line
			(start -0.12065 -0.2794)
			(end -0.12065 -0.3048)
			(stroke
				(width 0.1)
				(type default)
			)
			(layer "B.Fab")
		)
		(fp_line
			(start 0.12065 -0.2794)
			(end -0.12065 -0.2794)
			(stroke
				(width 0.1)
				(type default)
			)
			(layer "B.Fab")
		)
		(fp_line
			(start -0.67945 -0.3048)
			(end -0.67945 0.3048)
			(stroke
				(width 0.1)
				(type default)
			)
			(layer "B.Fab")
		)
		(fp_line
			(start -0.12065 -0.3048)
			(end -0.67945 -0.3048)
			(stroke
				(width 0.1)
				(type default)
			)
			(layer "B.Fab")
		)
		(fp_line
			(start 0.12065 -0.305054)
			(end 0.12065 -0.2794)
			(stroke
				(width 0.1)
				(type default)
			)
			(layer "B.Fab")
		)
		(fp_line
			(start 0.67945 -0.305054)
			(end 0.12065 -0.305054)
			(stroke
				(width 0.1)
				(type default)
			)
			(layer "B.Fab")
		)
		(pad "1" smd circle
			(at 0.40005 0 90)
			(size 0 0)
			(layers "B.Cu" "B.Mask" "B.Paste")
			(net "PVNN_TERM_CPU1")
		)
		(pad "2" smd circle
			(at -0.40005 0 90)
			(size 0 0)
			(layers "B.Cu" "B.Mask" "B.Paste")
			(net "DBP_CPU_MBP1_GTL_N")
		)
	)
	(footprint ""
		(layer "B.Cu")
		(at 307.069998 -192.60947 90)
		(property "Reference" "R15"
			(at 0 0 90)
			(layer "B.SilkS")
			(hide yes)
			(effects
				(font
					(size 1.27 1.27)
				)
				(justify mirror)
			)
		)
		(property "Value" ""
			(at 0 0 90)
			(layer "B.Fab")
			(effects
				(font
					(size 1.27 1.27)
				)
				(justify mirror)
			)
		)
		(duplicate_pad_numbers_are_jumpers no)
		(fp_line
			(start 0.7874 -0.4064)
			(end -0.7874 -0.4064)
			(stroke
				(width 0.1524)
				(type default)
			)
			(layer "B.SilkS")
		)
		(fp_line
			(start -0.7874 -0.4064)
			(end -0.7874 0.4064)
			(stroke
				(width 0.1524)
				(type default)
			)
			(layer "B.SilkS")
		)
		(fp_line
			(start 0.7874 0.4064)
			(end 0.7874 -0.4064)
			(stroke
				(width 0.1524)
				(type default)
			)
			(layer "B.SilkS")
		)
		(fp_line
			(start -0.7874 0.4064)
			(end 0.7874 0.4064)
			(stroke
				(width 0.1524)
				(type default)
			)
			(layer "B.SilkS")
		)
		(fp_line
			(start 0.67945 -0.305054)
			(end 0.12065 -0.305054)
			(stroke
				(width 0.1)
				(type default)
			)
			(layer "B.Fab")
		)
		(fp_line
			(start 0.12065 -0.305054)
			(end 0.12065 -0.2794)
			(stroke
				(width 0.1)
				(type default)
			)
			(layer "B.Fab")
		)
		(fp_line
			(start -0.12065 -0.3048)
			(end -0.67945 -0.3048)
			(stroke
				(width 0.1)
				(type default)
			)
			(layer "B.Fab")
		)
		(fp_line
			(start -0.67945 -0.3048)
			(end -0.67945 0.3048)
			(stroke
				(width 0.1)
				(type default)
			)
			(layer "B.Fab")
		)
		(fp_line
			(start 0.12065 -0.2794)
			(end -0.12065 -0.2794)
			(stroke
				(width 0.1)
				(type default)
			)
			(layer "B.Fab")
		)
		(fp_line
			(start -0.12065 -0.2794)
			(end -0.12065 -0.3048)
			(stroke
				(width 0.1)
				(type default)
			)
			(layer "B.Fab")
		)
		(fp_line
			(start 0.12065 0.2794)
			(end 0.12065 0.3048)
			(stroke
				(width 0.1)
				(type default)
			)
			(layer "B.Fab")
		)
		(fp_line
			(start -0.120396 0.2794)
			(end 0.12065 0.2794)
			(stroke
				(width 0.1)
				(type default)
			)
			(layer "B.Fab")
		)
		(fp_line
			(start 0.67945 0.3048)
			(end 0.67945 -0.305054)
			(stroke
				(width 0.1)
				(type default)
			)
			(layer "B.Fab")
		)
		(fp_line
			(start 0.12065 0.3048)
			(end 0.67945 0.3048)
			(stroke
				(width 0.1)
				(type default)
			)
			(layer "B.Fab")
		)
		(fp_line
			(start -0.120396 0.3048)
			(end -0.120396 0.2794)
			(stroke
				(width 0.1)
				(type default)
			)
			(layer "B.Fab")
		)
		(fp_line
			(start -0.67945 0.3048)
			(end -0.120396 0.3048)
			(stroke
				(width 0.1)
				(type default)
			)
			(layer "B.Fab")
		)
		(pad "1" smd circle
			(at 0.40005 0 270)
			(size 0 0)
			(layers "B.Cu" "B.Mask" "B.Paste")
			(net "SVID_DIO1_CPU0")
		)
		(pad "2" smd circle
			(at -0.40005 0 270)
			(size 0 0)
			(layers "B.Cu" "B.Mask" "B.Paste")
			(net "SVID_DIO1_CPU0_R")
		)
	)
)
